# BASEBOARD_FAB2 (Tioga Pass) — schematic netlist excerpt (pin names and nets, part order shuffled) for the footprints in the layout excerpt that follows; sources: Cadence DE-HDL packaged netlist, KiCad conversion of Wiwynn_Tioga_Pass_MB.brd

J4G3  SCONN288_H44441004  SCONN  pkg PIP  page 47
  \12v\(1)  = P12V_NVDIMM_ABC
  VSS(93)  = GND
  DQ(4)  = M_C_DQ<5>
  VSS(92)  = GND
  DQ(0)  = M_C_DQ<1>
  VSS(91)  = GND
  DQS9P  = M_C_DQS_DP<9>
  DQS9N  = M_C_DQS_DN<9>
  VSS(90)  = GND
  DQ(6)  = M_C_DQ<7>
  VSS(89)  = GND
  DQ(2)  = M_C_DQ<3>
  VSS(88)  = GND
  DQ(12)  = M_C_DQ<13>
  VSS(87)  = GND
  DQ(8)  = M_C_DQ<9>
  VSS(86)  = GND
  DQS10P  = M_C_DQS_DP<10>
  DQS10N  = M_C_DQS_DN<10>
  VSS(85)  = GND
  DQ(14)  = M_C_DQ<15>
  VSS(84)  = GND
  DQ(10)  = M_C_DQ<11>
  VSS(83)  = GND
  DQ(20)  = M_C_DQ<21>
  VSS(82)  = GND
  DQ(16)  = M_C_DQ<17>
  VSS(81)  = GND
  DQS11P  = M_C_DQS_DP<11>
  DQS11N  = M_C_DQS_DN<11>
  VSS(80)  = GND
  DQ(22)  = M_C_DQ<23>
  VSS(79)  = GND
  DQ(18)  = M_C_DQ<19>
  VSS(78)  = GND
  DQ(28)  = M_C_DQ<29>
  VSS(77)  = GND
  DQ(24)  = M_C_DQ<25>
  VSS(76)  = GND
  DQS12P  = M_C_DQS_DP<12>
  DQS12N  = M_C_DQS_DN<12>
  VSS(75)  = GND
  DQ(30)  = M_C_DQ<31>
  VSS(74)  = GND
  DQ(26)  = M_C_DQ<27>
  VSS(73)  = GND
  CB(4)  = M_C_ECC<5>
  VSS(72)  = GND
  CB(0)  = M_C_ECC<1>
  VSS(71)  = GND
  DQS17P  = M_C_DQS_DP<17>
  DQS17N  = M_C_DQS_DN<17>
  VSS(70)  = GND
  CB(6)  = M_C_ECC<7>
  VSS(69)  = GND
  CB(2)  = M_C_ECC<3>
  VSS(68)  = GND
  RESET_N  = M_ABC_RST_N
  VDD(25)  = PVDDQ_ABC
  CKE(0)  = M_C_CKE<0>
  VDD(24)  = PVDDQ_ABC
  ACT_N  = M_C_ACT_N
  BG(0)  = M_C_BG<0>
  VDD(23)  = PVDDQ_ABC
  A12  = M_C_MA<12>
  A9  = M_C_MA<9>
  VDD(22)  = PVDDQ_ABC
  A8  = M_C_MA<8>
  A6  = M_C_MA<6>
  VDD(21)  = PVDDQ_ABC
  A3  = M_C_MA<3>
  A1  = M_C_MA<1>
  VDD(20)  = PVDDQ_ABC
  CK0P  = M_C_CLK_DP<0>
  CK0N  = M_C_CLK_DN<0>
  VDD(19)  = PVDDQ_ABC
  VTT(1)  = PVTT_ABC
  EVENT_N  = FM_DIMM_EVENT_COD_N
  A0  = M_C_MA<0>
  VDD(18)  = PVDDQ_ABC
  BA(0)  = M_C_BA<0>
  A16_RAS_N  = M_C_MA<16>
  VDD(17)  = PVDDQ_ABC
  S0_N  = M_C_CS_N<0>
  VDD(16)  = PVDDQ_ABC
  A15_CAS_N  = M_C_MA<15>
  ODT(0)  = M_C_ODT<0>
  VDD(15)  = PVDDQ_ABC
  S1_N  = M_C_CS_N<1>
  VDD(14)  = PVDDQ_ABC
  ODT(1)  = M_C_ODT<1>
  VDD(13)  = PVDDQ_ABC
  S2_N_C(0)  = M_C_CS_N<2>
  VSS(67)  = GND
  DQ(36)  = M_C_DQ<37>
  VSS(66)  = GND
  DQ(32)  = M_C_DQ<33>
  VSS(65)  = GND
  DQS13P  = M_C_DQS_DP<13>
  DQS13N  = M_C_DQS_DN<13>
  VSS(64)  = GND
  DQ(38)  = M_C_DQ<39>
  VSS(63)  = GND
  DQ(34)  = M_C_DQ<35>
  VSS(62)  = GND
  DQ(44)  = M_C_DQ<45>
  VSS(61)  = GND
  DQ(40)  = M_C_DQ<41>
  VSS(60)  = GND
  DQS14P  = M_C_DQS_DP<14>
  DQS14N  = M_C_DQS_DN<14>
  VSS(59)  = GND
  DQ(46)  = M_C_DQ<47>
  VSS(58)  = GND
  DQ(42)  = M_C_DQ<43>
  VSS(57)  = GND
  DQ(52)  = M_C_DQ<53>
  VSS(56)  = GND
  DQ(48)  = M_C_DQ<49>
  VSS(55)  = GND
  DQS15P  = M_C_DQS_DP<15>
  DQS15N  = M_C_DQS_DN<15>
  VSS(54)  = GND
  DQ(54)  = M_C_DQ<55>
  VSS(53)  = GND
  DQ(50)  = M_C_DQ<51>
  VSS(52)  = GND
  DQ(60)  = M_C_DQ<61>
  VSS(51)  = GND
  DQ(56)  = M_C_DQ<57>
  VSS(50)  = GND
  DQS16P  = M_C_DQS_DP<16>
  DQS16N  = M_C_DQS_DN<16>
  VSS(49)  = GND
  DQ(62)  = M_C_DQ<63>
  VSS(48)  = GND
  DQ(58)  = M_C_DQ<59>
  VSS(47)  = GND
  SA(0)  = GND
  SA(1)  = GND
  SCL  = SMB_DDR_ABC_VPP_SCL
  VPP(4)  = PVPP_ABC
  VPP(3)  = PVPP_ABC
  RFU(2)  = TP_CH_C_DIMM_C0_RFU_2
  \12v\(0)  = P12V_NVDIMM_ABC
  VREFCA  = M_C_VREF
  VSS(46)  = GND
  DQ(5)  = M_C_DQ<4>
  VSS(45)  = GND
  DQ(1)  = M_C_DQ<0>
  VSS(44)  = GND
  DQS0N  = M_C_DQS_DN<0>
  DQS0P  = M_C_DQS_DP<0>
  VSS(43)  = GND
  DQ(7)  = M_C_DQ<6>
  VSS(42)  = GND
  DQ(3)  = M_C_DQ<2>
  VSS(41)  = GND
  DQ(13)  = M_C_DQ<12>
  VSS(40)  = GND
  DQ(9)  = M_C_DQ<8>
  VSS(39)  = GND
  DQS1N  = M_C_DQS_DN<1>
  DQS1P  = M_C_DQS_DP<1>
  VSS(38)  = GND
  DQ(15)  = M_C_DQ<14>
  VSS(37)  = GND
  DQ(11)  = M_C_DQ<10>
  VSS(36)  = GND
  DQ(21)  = M_C_DQ<20>
  VSS(35)  = GND
  DQ(17)  = M_C_DQ<16>
  VSS(34)  = GND
  DQS2N  = M_C_DQS_DN<2>
  DQS2P  = M_C_DQS_DP<2>
  VSS(33)  = GND
  DQ(23)  = M_C_DQ<22>
  VSS(32)  = GND
  DQ(19)  = M_C_DQ<18>
  VSS(31)  = GND
  DQ(29)  = M_C_DQ<28>
  VSS(30)  = GND
  DQ(25)  = M_C_DQ<24>
  VSS(29)  = GND
  DQS3N  = M_C_DQS_DN<3>
  DQS3P  = M_C_DQS_DP<3>
  VSS(28)  = GND
  DQ(31)  = M_C_DQ<30>
  VSS(27)  = GND
  DQ(27)  = M_C_DQ<26>
  VSS(26)  = GND
  CB(5)  = M_C_ECC<4>
  VSS(25)  = GND
  CB(1)  = M_C_ECC<0>
  VSS(24)  = GND
  DQS8N  = M_C_DQS_DN<8>
  DQS8P  = M_C_DQS_DP<8>
  VSS(23)  = GND
  CB(7)  = M_C_ECC<6>
  VSS(22)  = GND
  CB(3)  = M_C_ECC<2>
  VSS(21)  = GND
  CKE(1)  = M_C_CKE<1>
  VDD(12)  = PVDDQ_ABC
  RFU(0)  = TP_CH_C_DIMM_C0_RFU_0
  VDD(11)  = PVDDQ_ABC
  BG(1)  = M_C_BG<1>
  ALERT_N  = M_C_ALERT_N
  VDD(10)  = PVDDQ_ABC
  A11  = M_C_MA<11>
  A7  = M_C_MA<7>
  VDD(9)  = PVDDQ_ABC
  A5  = M_C_MA<5>
  A4  = M_C_MA<4>
  VDD(8)  = PVDDQ_ABC
  A2  = M_C_MA<2>
  VDD(7)  = PVDDQ_ABC
  CK1P  = M_C_CLK_DP<1>
  CK1N  = M_C_CLK_DN<1>
  VDD(6)  = PVDDQ_ABC
  VTT(0)  = PVTT_ABC
  PAR  = M_C_PAR
  VDD(5)  = PVDDQ_ABC
  BA(1)  = M_C_BA<1>
  A10  = M_C_MA<10>
  VDD(4)  = PVDDQ_ABC
  RFU(1)  = TP_CH_C_DIMM_C0_RFU_1
  A14_WE_N  = M_C_MA<14>
  VDD(3)  = PVDDQ_ABC
  SAVE_N_NC  = FM_ADR_COMPLETE_ABC_N
  VDD(2)  = PVDDQ_ABC
  A13  = M_C_MA<13>
  VDD(1)  = PVDDQ_ABC
  A17  = M_C_MA<17>
  C(2)  = M_C_C<2>
  VDD(0)  = PVDDQ_ABC
  S3_N_C(1)  = M_C_CS_N<3>
  SA(2)  = PVPP_ABC
  VSS(20)  = GND
  DQ(37)  = M_C_DQ<36>
  VSS(19)  = GND
  DQ(33)  = M_C_DQ<32>
  VSS(18)  = GND
  DQS4N  = M_C_DQS_DN<4>
  DQS4P  = M_C_DQS_DP<4>
  VSS(17)  = GND
  DQ(39)  = M_C_DQ<38>
  VSS(16)  = GND
  DQ(35)  = M_C_DQ<34>
  VSS(15)  = GND
  DQ(45)  = M_C_DQ<44>
  VSS(14)  = GND
  DQ(41)  = M_C_DQ<40>
  VSS(13)  = GND
  DQS5N  = M_C_DQS_DN<5>
  DQS5P  = M_C_DQS_DP<5>
  VSS(12)  = GND
  DQ(47)  = M_C_DQ<46>
  VSS(11)  = GND
  DQ(43)  = M_C_DQ<42>
  VSS(10)  = GND
  DQ(53)  = M_C_DQ<52>
  VSS(9)  = GND
  DQ(49)  = M_C_DQ<48>
  VSS(8)  = GND
  DQS6N  = M_C_DQS_DN<6>
  DQS6P  = M_C_DQS_DP<6>
  VSS(7)  = GND
  DQ(55)  = M_C_DQ<54>
  VSS(6)  = GND
  DQ(51)  = M_C_DQ<50>
  VSS(5)  = GND
  DQ(61)  = M_C_DQ<60>
  VSS(4)  = GND
  DQ(57)  = M_C_DQ<56>
  VSS(3)  = GND
  DQS7N  = M_C_DQS_DN<7>
  DQS7P  = M_C_DQS_DP<7>
  VSS(2)  = GND
  DQ(63)  = M_C_DQ<62>
  VSS(1)  = GND
  DQ(59)  = M_C_DQ<58>
  VSS(0)  = GND
  VDDSPD  = PVPP_ABC
  SDA  = SMB_DDR_ABC_VPP_SDA
  VPP(1)  = PVPP_ABC
  VPP(0)  = PVPP_ABC
  VPP(2)  = PVPP_ABC

(kicad_pcb
	(version 20260206)
	(generator "pcbnew")
	(generator_version "10.0")
	(general
		(thickness 1.6)
		(legacy_teardrops no)
	)
	(paper "A4")
	(title_block
		(title "Wiwynn_Tioga_Pass_MB.brd")
		(comment 1 "Tioga Pass / footprint 1441 of 4770 (J4G3), pads 153-202 of 291")
	)
	(layers
		(0 "F.Cu" signal "TOP")
		(4 "In1.Cu" signal "L2GND")
		(6 "In2.Cu" signal "L3")
		(8 "In3.Cu" signal "L4GND")
		(10 "In4.Cu" signal "L5")
		(12 "In5.Cu" signal "L6GND")
		(14 "In6.Cu" signal "L7VCC")
		(16 "In7.Cu" signal "L8VCC")
		(18 "In8.Cu" signal "L9GND")
		(20 "In9.Cu" signal "L10")
		(22 "In10.Cu" signal "L11GND")
		(24 "In11.Cu" signal "L12")
		(26 "In12.Cu" signal "L13GND")
		(2 "B.Cu" signal "BOTTOM")
		(9 "F.Adhes" user "F.Adhesive")
		(11 "B.Adhes" user "B.Adhesive")
		(13 "F.Paste" user "Package Geometry/Pastemask Top")
		(15 "B.Paste" user "Package Geometry/Pastemask Bottom")
		(5 "F.SilkS" user "Ref Des/Silkscreen Top")
		(7 "B.SilkS" user "Ref Des/Silkscreen Bottom")
		(1 "F.Mask" user "Board Geometry/Soldermask Top")
		(3 "B.Mask" user "Board Geometry/Soldermask Bottom")
		(17 "Dwgs.User" user "User.Drawings")
		(19 "Cmts.User" user "User.Comments")
		(21 "Eco1.User" user "User.Eco1")
		(23 "Eco2.User" user "User.Eco2")
		(25 "Edge.Cuts" user "Board Geometry/Outline")
		(27 "Margin" user)
		(31 "F.CrtYd" user "Package Geometry/Place Bound Top")
		(29 "B.CrtYd" user "Package Geometry/Place Bound Bottom")
		(35 "F.Fab" user "Ref Des/Assembly Top")
		(33 "B.Fab" user "Ref Des/Assembly Bottom")
	)
	(footprint ""
		(layer "F.Cu")
		(at 194.700398 3.778758 90)
		(property "Reference" "J4G3"
			(at 6.800088 37.20211 0)
			(unlocked yes)
			(layer "F.SilkS")
			(effects
				(font
					(size 0.7874 0.5842)
					(thickness 0.1524)
				)
				(justify left)
			)
		)
		(property "Value" ""
			(at 0 0 90)
			(layer "F.Fab")
			(effects
				(font
					(size 1.27 1.27)
				)
			)
		)
		(duplicate_pad_numbers_are_jumpers no)
		(pad "150" smd rect
			(at 4.59994 4.249928 90)
			(size 1.8034 0.508)
			(layers "F.Cu" "F.Mask" "F.Paste")
			(net "M_C_DQ<0>")
		)
		(pad "151" smd rect
			(at 4.59994 5.100066 90)
			(size 1.8034 0.508)
			(layers "F.Cu" "F.Mask" "F.Paste")
			(net "GND")
		)
		(pad "152" smd rect
			(at 4.59994 5.94995 90)
			(size 1.8034 0.508)
			(layers "F.Cu" "F.Mask" "F.Paste")
			(net "M_C_DQS_DN<0>")
		)
		(pad "153" smd rect
			(at 4.59994 6.800088 90)
			(size 1.8034 0.508)
			(layers "F.Cu" "F.Mask" "F.Paste")
			(net "M_C_DQS_DP<0>")
		)
		(pad "154" smd rect
			(at 4.59994 7.649972 90)
			(size 1.8034 0.508)
			(layers "F.Cu" "F.Mask" "F.Paste")
			(net "GND")
		)
		(pad "155" smd rect
			(at 4.59994 8.50011 90)
			(size 1.8034 0.508)
			(layers "F.Cu" "F.Mask" "F.Paste")
			(net "M_C_DQ<6>")
		)
		(pad "156" smd rect
			(at 4.59994 9.349994 90)
			(size 1.8034 0.508)
			(layers "F.Cu" "F.Mask" "F.Paste")
			(net "GND")
		)
		(pad "157" smd rect
			(at 4.59994 10.199878 90)
			(size 1.8034 0.508)
			(layers "F.Cu" "F.Mask" "F.Paste")
			(net "M_C_DQ<2>")
		)
		(pad "158" smd rect
			(at 4.59994 11.050016 90)
			(size 1.8034 0.508)
			(layers "F.Cu" "F.Mask" "F.Paste")
			(net "GND")
		)
		(pad "159" smd rect
			(at 4.59994 11.8999 90)
			(size 1.8034 0.508)
			(layers "F.Cu" "F.Mask" "F.Paste")
			(net "M_C_DQ<12>")
		)
		(pad "160" smd rect
			(at 4.59994 12.750038 90)
			(size 1.8034 0.508)
			(layers "F.Cu" "F.Mask" "F.Paste")
			(net "GND")
		)
		(pad "161" smd rect
			(at 4.59994 13.599922 90)
			(size 1.8034 0.508)
			(layers "F.Cu" "F.Mask" "F.Paste")
			(net "M_C_DQ<8>")
		)
		(pad "162" smd rect
			(at 4.59994 14.45006 90)
			(size 1.8034 0.508)
			(layers "F.Cu" "F.Mask" "F.Paste")
			(net "GND")
		)
		(pad "163" smd rect
			(at 4.59994 15.299944 90)
			(size 1.8034 0.508)
			(layers "F.Cu" "F.Mask" "F.Paste")
			(net "M_C_DQS_DN<1>")
		)
		(pad "164" smd rect
			(at 4.59994 16.150082 90)
			(size 1.8034 0.508)
			(layers "F.Cu" "F.Mask" "F.Paste")
			(net "M_C_DQS_DP<1>")
		)
		(pad "165" smd rect
			(at 4.59994 16.999966 90)
			(size 1.8034 0.508)
			(layers "F.Cu" "F.Mask" "F.Paste")
			(net "GND")
		)
		(pad "166" smd rect
			(at 4.59994 17.850104 90)
			(size 1.8034 0.508)
			(layers "F.Cu" "F.Mask" "F.Paste")
			(net "M_C_DQ<14>")
		)
		(pad "167" smd rect
			(at 4.59994 18.699988 90)
			(size 1.8034 0.508)
			(layers "F.Cu" "F.Mask" "F.Paste")
			(net "GND")
		)
		(pad "168" smd rect
			(at 4.59994 19.550126 90)
			(size 1.8034 0.508)
			(layers "F.Cu" "F.Mask" "F.Paste")
			(net "M_C_DQ<10>")
		)
		(pad "169" smd rect
			(at 4.59994 20.40001 90)
			(size 1.8034 0.508)
			(layers "F.Cu" "F.Mask" "F.Paste")
			(net "GND")
		)
		(pad "170" smd rect
			(at 4.59994 21.249894 90)
			(size 1.8034 0.508)
			(layers "F.Cu" "F.Mask" "F.Paste")
			(net "M_C_DQ<20>")
		)
		(pad "171" smd rect
			(at 4.59994 22.100032 90)
			(size 1.8034 0.508)
			(layers "F.Cu" "F.Mask" "F.Paste")
			(net "GND")
		)
		(pad "172" smd rect
			(at 4.59994 22.949916 90)
			(size 1.8034 0.508)
			(layers "F.Cu" "F.Mask" "F.Paste")
			(net "M_C_DQ<16>")
		)
		(pad "173" smd rect
			(at 4.59994 23.800054 90)
			(size 1.8034 0.508)
			(layers "F.Cu" "F.Mask" "F.Paste")
			(net "GND")
		)
		(pad "174" smd rect
			(at 4.59994 24.649938 90)
			(size 1.8034 0.508)
			(layers "F.Cu" "F.Mask" "F.Paste")
			(net "M_C_DQS_DN<2>")
		)
		(pad "175" smd rect
			(at 4.59994 25.500076 90)
			(size 1.8034 0.508)
			(layers "F.Cu" "F.Mask" "F.Paste")
			(net "M_C_DQS_DP<2>")
		)
		(pad "176" smd rect
			(at 4.59994 26.34996 90)
			(size 1.8034 0.508)
			(layers "F.Cu" "F.Mask" "F.Paste")
			(net "GND")
		)
		(pad "177" smd rect
			(at 4.59994 27.200098 90)
			(size 1.8034 0.508)
			(layers "F.Cu" "F.Mask" "F.Paste")
			(net "M_C_DQ<22>")
		)
		(pad "178" smd rect
			(at 4.59994 28.049982 90)
			(size 1.8034 0.508)
			(layers "F.Cu" "F.Mask" "F.Paste")
			(net "GND")
		)
		(pad "179" smd rect
			(at 4.59994 28.90012 90)
			(size 1.8034 0.508)
			(layers "F.Cu" "F.Mask" "F.Paste")
			(net "M_C_DQ<18>")
		)
		(pad "180" smd rect
			(at 4.59994 29.750004 90)
			(size 1.8034 0.508)
			(layers "F.Cu" "F.Mask" "F.Paste")
			(net "GND")
		)
		(pad "181" smd rect
			(at 4.59994 30.599888 90)
			(size 1.8034 0.508)
			(layers "F.Cu" "F.Mask" "F.Paste")
			(net "M_C_DQ<28>")
		)
		(pad "182" smd rect
			(at 4.59994 31.450026 90)
			(size 1.8034 0.508)
			(layers "F.Cu" "F.Mask" "F.Paste")
			(net "GND")
		)
		(pad "183" smd rect
			(at 4.59994 32.29991 90)
			(size 1.8034 0.508)
			(layers "F.Cu" "F.Mask" "F.Paste")
			(net "M_C_DQ<24>")
		)
		(pad "184" smd rect
			(at 4.59994 33.150048 90)
			(size 1.8034 0.508)
			(layers "F.Cu" "F.Mask" "F.Paste")
			(net "GND")
		)
		(pad "185" smd rect
			(at 4.59994 33.999932 90)
			(size 1.8034 0.508)
			(layers "F.Cu" "F.Mask" "F.Paste")
			(net "M_C_DQS_DN<3>")
		)
		(pad "186" smd rect
			(at 4.59994 34.85007 90)
			(size 1.8034 0.508)
			(layers "F.Cu" "F.Mask" "F.Paste")
			(net "M_C_DQS_DP<3>")
		)
		(pad "187" smd rect
			(at 4.59994 35.699954 90)
			(size 1.8034 0.508)
			(layers "F.Cu" "F.Mask" "F.Paste")
			(net "GND")
		)
		(pad "188" smd rect
			(at 4.59994 36.550092 90)
			(size 1.8034 0.508)
			(layers "F.Cu" "F.Mask" "F.Paste")
			(net "M_C_DQ<30>")
		)
		(pad "189" smd rect
			(at 4.59994 37.399976 90)
			(size 1.8034 0.508)
			(layers "F.Cu" "F.Mask" "F.Paste")
			(net "GND")
		)
		(pad "190" smd rect
			(at 4.59994 38.250114 90)
			(size 1.8034 0.508)
			(layers "F.Cu" "F.Mask" "F.Paste")
			(net "M_C_DQ<26>")
		)
		(pad "191" smd rect
			(at 4.59994 39.099998 90)
			(size 1.8034 0.508)
			(layers "F.Cu" "F.Mask" "F.Paste")
			(net "GND")
		)
		(pad "192" smd rect
			(at 4.59994 39.949882 90)
			(size 1.8034 0.508)
			(layers "F.Cu" "F.Mask" "F.Paste")
			(net "M_C_ECC<4>")
		)
		(pad "193" smd rect
			(at 4.59994 40.80002 90)
			(size 1.8034 0.508)
			(layers "F.Cu" "F.Mask" "F.Paste")
			(net "GND")
		)
		(pad "194" smd rect
			(at 4.59994 41.649904 90)
			(size 1.8034 0.508)
			(layers "F.Cu" "F.Mask" "F.Paste")
			(net "M_C_ECC<0>")
		)
		(pad "195" smd rect
			(at 4.59994 42.500042 90)
			(size 1.8034 0.508)
			(layers "F.Cu" "F.Mask" "F.Paste")
			(net "GND")
		)
		(pad "196" smd rect
			(at 4.59994 43.349926 90)
			(size 1.8034 0.508)
			(layers "F.Cu" "F.Mask" "F.Paste")
			(net "M_C_DQS_DN<8>")
		)
		(pad "197" smd rect
			(at 4.59994 44.200064 90)
			(size 1.8034 0.508)
			(layers "F.Cu" "F.Mask" "F.Paste")
			(net "M_C_DQS_DP<8>")
		)
		(pad "198" smd rect
			(at 4.59994 45.049948 90)
			(size 1.8034 0.508)
			(layers "F.Cu" "F.Mask" "F.Paste")
			(net "GND")
		)
		(pad "199" smd rect
			(at 4.59994 45.900086 90)
			(size 1.8034 0.508)
			(layers "F.Cu" "F.Mask" "F.Paste")
			(net "M_C_ECC<6>")
		)
	)
)
